# T6G (Grand Teton) — schematic netlist excerpt (pin names and nets, part order shuffled) for the footprints in the layout excerpt that follows; sources: Cadence DE-HDL packaged netlist, KiCad conversion of 04192023_DAF0TMB3IC0_F0TG_MB_C_brd_V02_OCP.brd

R382  Q_RES  15 1% CHIP  pkg 0402LF  page 17 : A = M_H_CPU0_ALERT_N ; B = M_H_CPU0_ALERT_R_N
PR6500  Q_RES  0 5% CHIP  pkg 0402LF  page 360 : A = GND ; B = P1V8_RETIMER_CPU0_MODE
C1020  Q_CAP  1UF 4V 20% X6S  pkg 0201  page 312 : A = P0V9_CPU0_RT3_2A_2D ; B = GND

(kicad_pcb
	(version 20260206)
	(generator "pcbnew")
	(generator_version "10.0")
	(general
		(thickness 1.6)
		(legacy_teardrops no)
	)
	(paper "A4")
	(title_block
		(title "04192023_DAF0TMB3IC0_F0TG_MB_C_brd_V02_OCP.brd")
		(comment 1 "Grand Teton / footprints 6761-6763 of 8354")
	)
	(layers
		(0 "F.Cu" signal "TOP")
		(4 "In1.Cu" signal "GND")
		(6 "In2.Cu" signal "IN1")
		(8 "In3.Cu" signal "GND1")
		(10 "In4.Cu" signal "IN2")
		(12 "In5.Cu" signal "GND2")
		(14 "In6.Cu" signal "IN3")
		(16 "In7.Cu" signal "GND3")
		(18 "In8.Cu" signal "VCC")
		(20 "In9.Cu" signal "VCC1")
		(22 "In10.Cu" signal "GND4")
		(24 "In11.Cu" signal "IN4")
		(26 "In12.Cu" signal "GND5")
		(28 "In13.Cu" signal "IN5")
		(30 "In14.Cu" signal "GND6")
		(32 "In15.Cu" signal "IN6")
		(34 "In16.Cu" signal "GND7")
		(2 "B.Cu" signal "BOTTOM")
		(9 "F.Adhes" user "F.Adhesive")
		(11 "B.Adhes" user "B.Adhesive")
		(13 "F.Paste" user "Package Geometry/Pastemask Top")
		(15 "B.Paste" user "Package Geometry/Pastemask Bottom")
		(5 "F.SilkS" user "Ref Des/Silkscreen Top")
		(7 "B.SilkS" user "Ref Des/Silkscreen Bottom")
		(1 "F.Mask" user "Board Geometry/Soldermask Top")
		(3 "B.Mask" user "Board Geometry/Soldermask Bottom")
		(17 "Dwgs.User" user "User.Drawings")
		(19 "Cmts.User" user "User.Comments")
		(21 "Eco1.User" user "User.Eco1")
		(23 "Eco2.User" user "User.Eco2")
		(25 "Edge.Cuts" user "Board Geometry/Outline")
		(27 "Margin" user)
		(31 "F.CrtYd" user "Package Geometry/Place Bound Top")
		(29 "B.CrtYd" user "Package Geometry/Place Bound Bottom")
		(35 "F.Fab" user "Ref Des/Assembly Top")
		(33 "B.Fab" user "Ref Des/Assembly Bottom")
	)
	(footprint ""
		(layer "B.Cu")
		(at 375.278396 -395.148562 90)
		(property "Reference" "C1020"
			(at 0 0 90)
			(layer "B.SilkS")
			(hide yes)
			(effects
				(font
					(size 1.27 1.27)
				)
				(justify mirror)
			)
		)
		(property "Value" ""
			(at 0 0 90)
			(layer "B.Fab")
			(effects
				(font
					(size 1.27 1.27)
				)
				(justify mirror)
			)
		)
		(duplicate_pad_numbers_are_jumpers no)
		(fp_line
			(start 0.299974 -0.150114)
			(end -0.299974 -0.150114)
			(stroke
				(width 0.1)
				(type default)
			)
			(layer "B.Fab")
		)
		(fp_line
			(start -0.299974 -0.150114)
			(end -0.299974 0.150114)
			(stroke
				(width 0.1)
				(type default)
			)
			(layer "B.Fab")
		)
		(fp_line
			(start 0.299974 0.150114)
			(end 0.299974 -0.150114)
			(stroke
				(width 0.1)
				(type default)
			)
			(layer "B.Fab")
		)
		(fp_line
			(start -0.299974 0.150114)
			(end 0.299974 0.150114)
			(stroke
				(width 0.1)
				(type default)
			)
			(layer "B.Fab")
		)
		(pad "1" smd rect
			(at 0.2667 0 270)
			(size 0.3048 0.381)
			(layers "B.Cu" "B.Mask" "B.Paste")
			(net "P0V9_CPU0_RT3_2A_2D")
		)
		(pad "2" smd rect
			(at -0.2667 0 270)
			(size 0.3048 0.381)
			(layers "B.Cu" "B.Mask" "B.Paste")
			(net "GND")
		)
	)
	(footprint ""
		(layer "B.Cu")
		(at 240.327942 -290.564062)
		(property "Reference" "PR6500"
			(at 0 0 0)
			(layer "B.SilkS")
			(hide yes)
			(effects
				(font
					(size 1.27 1.27)
				)
				(justify mirror)
			)
		)
		(property "Value" ""
			(at 0 0 0)
			(layer "B.Fab")
			(effects
				(font
					(size 1.27 1.27)
				)
				(justify mirror)
			)
		)
		(duplicate_pad_numbers_are_jumpers no)
		(fp_line
			(start -0.7874 -0.4064)
			(end -0.7874 0.4064)
			(stroke
				(width 0.1524)
				(type default)
			)
			(layer "B.SilkS")
		)
		(fp_line
			(start -0.7874 0.4064)
			(end 0.7874 0.4064)
			(stroke
				(width 0.1524)
				(type default)
			)
			(layer "B.SilkS")
		)
		(fp_line
			(start 0.7874 -0.4064)
			(end -0.7874 -0.4064)
			(stroke
				(width 0.1524)
				(type default)
			)
			(layer "B.SilkS")
		)
		(fp_line
			(start 0.7874 0.4064)
			(end 0.7874 -0.4064)
			(stroke
				(width 0.1524)
				(type default)
			)
			(layer "B.SilkS")
		)
		(fp_line
			(start -0.67945 -0.3048)
			(end -0.67945 0.3048)
			(stroke
				(width 0.1)
				(type default)
			)
			(layer "B.Fab")
		)
		(fp_line
			(start -0.67945 0.3048)
			(end -0.120396 0.3048)
			(stroke
				(width 0.1)
				(type default)
			)
			(layer "B.Fab")
		)
		(fp_line
			(start -0.12065 -0.3048)
			(end -0.67945 -0.3048)
			(stroke
				(width 0.1)
				(type default)
			)
			(layer "B.Fab")
		)
		(fp_line
			(start -0.12065 -0.2794)
			(end -0.12065 -0.3048)
			(stroke
				(width 0.1)
				(type default)
			)
			(layer "B.Fab")
		)
		(fp_line
			(start -0.120396 0.2794)
			(end 0.12065 0.2794)
			(stroke
				(width 0.1)
				(type default)
			)
			(layer "B.Fab")
		)
		(fp_line
			(start -0.120396 0.3048)
			(end -0.120396 0.2794)
			(stroke
				(width 0.1)
				(type default)
			)
			(layer "B.Fab")
		)
		(fp_line
			(start 0.12065 -0.305054)
			(end 0.12065 -0.2794)
			(stroke
				(width 0.1)
				(type default)
			)
			(layer "B.Fab")
		)
		(fp_line
			(start 0.12065 -0.2794)
			(end -0.12065 -0.2794)
			(stroke
				(width 0.1)
				(type default)
			)
			(layer "B.Fab")
		)
		(fp_line
			(start 0.12065 0.2794)
			(end 0.12065 0.3048)
			(stroke
				(width 0.1)
				(type default)
			)
			(layer "B.Fab")
		)
		(fp_line
			(start 0.12065 0.3048)
			(end 0.67945 0.3048)
			(stroke
				(width 0.1)
				(type default)
			)
			(layer "B.Fab")
		)
		(fp_line
			(start 0.67945 -0.305054)
			(end 0.12065 -0.305054)
			(stroke
				(width 0.1)
				(type default)
			)
			(layer "B.Fab")
		)
		(fp_line
			(start 0.67945 0.3048)
			(end 0.67945 -0.305054)
			(stroke
				(width 0.1)
				(type default)
			)
			(layer "B.Fab")
		)
		(pad "1" smd circle
			(at 0.40005 0 180)
			(size 0 0)
			(layers "B.Cu" "B.Mask" "B.Paste")
			(net "GND")
		)
		(pad "2" smd circle
			(at -0.40005 0 180)
			(size 0 0)
			(layers "B.Cu" "B.Mask" "B.Paste")
			(net "P1V8_RETIMER_CPU0_MODE")
		)
	)
	(footprint ""
		(layer "B.Cu")
		(at 423.015156 -244.08511)
		(property "Reference" "R382"
			(at 0 0 0)
			(layer "B.SilkS")
			(hide yes)
			(effects
				(font
					(size 1.27 1.27)
				)
				(justify mirror)
			)
		)
		(property "Value" ""
			(at 0 0 0)
			(layer "B.Fab")
			(effects
				(font
					(size 1.27 1.27)
				)
				(justify mirror)
			)
		)
		(duplicate_pad_numbers_are_jumpers no)
		(fp_line
			(start -0.7874 -0.4064)
			(end -0.7874 0.4064)
			(stroke
				(width 0.1524)
				(type default)
			)
			(layer "B.SilkS")
		)
		(fp_line
			(start -0.7874 0.4064)
			(end 0.7874 0.4064)
			(stroke
				(width 0.1524)
				(type default)
			)
			(layer "B.SilkS")
		)
		(fp_line
			(start 0.7874 -0.4064)
			(end -0.7874 -0.4064)
			(stroke
				(width 0.1524)
				(type default)
			)
			(layer "B.SilkS")
		)
		(fp_line
			(start 0.7874 0.4064)
			(end 0.7874 -0.4064)
			(stroke
				(width 0.1524)
				(type default)
			)
			(layer "B.SilkS")
		)
		(fp_line
			(start -0.67945 -0.3048)
			(end -0.67945 0.3048)
			(stroke
				(width 0.1)
				(type default)
			)
			(layer "B.Fab")
		)
		(fp_line
			(start -0.67945 0.3048)
			(end -0.120396 0.3048)
			(stroke
				(width 0.1)
				(type default)
			)
			(layer "B.Fab")
		)
		(fp_line
			(start -0.12065 -0.3048)
			(end -0.67945 -0.3048)
			(stroke
				(width 0.1)
				(type default)
			)
			(layer "B.Fab")
		)
		(fp_line
			(start -0.12065 -0.2794)
			(end -0.12065 -0.3048)
			(stroke
				(width 0.1)
				(type default)
			)
			(layer "B.Fab")
		)
		(fp_line
			(start -0.120396 0.2794)
			(end 0.12065 0.2794)
			(stroke
				(width 0.1)
				(type default)
			)
			(layer "B.Fab")
		)
		(fp_line
			(start -0.120396 0.3048)
			(end -0.120396 0.2794)
			(stroke
				(width 0.1)
				(type default)
			)
			(layer "B.Fab")
		)
		(fp_line
			(start 0.12065 -0.305054)
			(end 0.12065 -0.2794)
			(stroke
				(width 0.1)
				(type default)
			)
			(layer "B.Fab")
		)
		(fp_line
			(start 0.12065 -0.2794)
			(end -0.12065 -0.2794)
			(stroke
				(width 0.1)
				(type default)
			)
			(layer "B.Fab")
		)
		(fp_line
			(start 0.12065 0.2794)
			(end 0.12065 0.3048)
			(stroke
				(width 0.1)
				(type default)
			)
			(layer "B.Fab")
		)
		(fp_line
			(start 0.12065 0.3048)
			(end 0.67945 0.3048)
			(stroke
				(width 0.1)
				(type default)
			)
			(layer "B.Fab")
		)
		(fp_line
			(start 0.67945 -0.305054)
			(end 0.12065 -0.305054)
			(stroke
				(width 0.1)
				(type default)
			)
			(layer "B.Fab")
		)
		(fp_line
			(start 0.67945 0.3048)
			(end 0.67945 -0.305054)
			(stroke
				(width 0.1)
				(type default)
			)
			(layer "B.Fab")
		)
		(pad "1" smd circle
			(at 0.40005 0 180)
			(size 0 0)
			(layers "B.Cu" "B.Mask" "B.Paste")
			(net "M_H_CPU0_ALERT_N")
		)
		(pad "2" smd circle
			(at -0.40005 0 180)
			(size 0 0)
			(layers "B.Cu" "B.Mask" "B.Paste")
			(net "M_H_CPU0_ALERT_R_N")
		)
	)
)
